# SCM (Grand Teton) — schematic netlist excerpt (pin names and nets, part order shuffled) for the footprints in the layout excerpt that follows; sources: Cadence DE-HDL packaged netlist, KiCad conversion of 12092022_DA0F0TMDCD0_F0T_Management_Board_D_brd_V3_OCP.brd

R555  Q_RES  33.2 1% CHIP  pkg 0402LF  page 25 : A = FLASH_LATCH_Q_N_R ; B = FLASH_LATCH_Q_N_R1
R440  Q_RES  49.9 1% EMPTY  pkg 0402LF  page 15 : A = USB_HOST_BMC_A_DP ; B = GND

(kicad_pcb
	(version 20260206)
	(generator "pcbnew")
	(generator_version "10.0")
	(general
		(thickness 1.6)
		(legacy_teardrops no)
	)
	(paper "A4")
	(title_block
		(title "12092022_DA0F0TMDCD0_F0T_Management_Board_D_brd_V3_OCP.brd")
		(comment 1 "Grand Teton / footprints 424-425 of 1440")
	)
	(layers
		(0 "F.Cu" signal "TOP")
		(4 "In1.Cu" signal "GND")
		(6 "In2.Cu" signal "IN1")
		(8 "In3.Cu" signal "GND1")
		(10 "In4.Cu" signal "IN2")
		(12 "In5.Cu" signal "VCC")
		(14 "In6.Cu" signal "VCC1")
		(16 "In7.Cu" signal "IN3")
		(18 "In8.Cu" signal "GND2")
		(20 "In9.Cu" signal "IN4")
		(22 "In10.Cu" signal "GND3")
		(2 "B.Cu" signal "BOTTOM")
		(9 "F.Adhes" user "F.Adhesive")
		(11 "B.Adhes" user "B.Adhesive")
		(13 "F.Paste" user "Package Geometry/Pastemask Top")
		(15 "B.Paste" user "Package Geometry/Pastemask Bottom")
		(5 "F.SilkS" user "Ref Des/Silkscreen Top")
		(7 "B.SilkS" user "Ref Des/Silkscreen Bottom")
		(1 "F.Mask" user "Board Geometry/Soldermask Top")
		(3 "B.Mask" user "Board Geometry/Soldermask Bottom")
		(17 "Dwgs.User" user "User.Drawings")
		(19 "Cmts.User" user "User.Comments")
		(21 "Eco1.User" user "User.Eco1")
		(23 "Eco2.User" user "User.Eco2")
		(25 "Edge.Cuts" user "Board Geometry/Outline")
		(27 "Margin" user)
		(31 "F.CrtYd" user "Package Geometry/Place Bound Top")
		(29 "B.CrtYd" user "Package Geometry/Place Bound Bottom")
		(35 "F.Fab" user "Ref Des/Assembly Top")
		(33 "B.Fab" user "Ref Des/Assembly Bottom")
	)
	(footprint ""
		(layer "F.Cu")
		(at 64.4144 -28.0162 180)
		(property "Reference" "R440"
			(at 0 0 180)
			(layer "F.SilkS")
			(hide yes)
			(effects
				(font
					(size 1.27 1.27)
				)
			)
		)
		(property "Value" ""
			(at 0 0 180)
			(layer "F.Fab")
			(effects
				(font
					(size 1.27 1.27)
				)
			)
		)
		(duplicate_pad_numbers_are_jumpers no)
		(fp_line
			(start 0.7874 0.4064)
			(end -0.3048 0.4064)
			(stroke
				(width 0.1524)
				(type default)
			)
			(layer "F.SilkS")
		)
		(fp_line
			(start 0.7874 -0.4064)
			(end 0.7874 0.4064)
			(stroke
				(width 0.1524)
				(type default)
			)
			(layer "F.SilkS")
		)
		(fp_line
			(start -0.381 -0.4064)
			(end 0.7874 -0.4064)
			(stroke
				(width 0.1524)
				(type default)
			)
			(layer "F.SilkS")
		)
		(fp_line
			(start 0.67945 0.3048)
			(end 0.120396 0.3048)
			(stroke
				(width 0.1)
				(type default)
			)
			(layer "F.Fab")
		)
		(fp_line
			(start 0.67945 -0.3048)
			(end 0.67945 0.3048)
			(stroke
				(width 0.1)
				(type default)
			)
			(layer "F.Fab")
		)
		(fp_line
			(start 0.12065 -0.2794)
			(end 0.12065 -0.3048)
			(stroke
				(width 0.1)
				(type default)
			)
			(layer "F.Fab")
		)
		(fp_line
			(start 0.12065 -0.3048)
			(end 0.67945 -0.3048)
			(stroke
				(width 0.1)
				(type default)
			)
			(layer "F.Fab")
		)
		(fp_line
			(start 0.120396 0.3048)
			(end 0.120396 0.2794)
			(stroke
				(width 0.1)
				(type default)
			)
			(layer "F.Fab")
		)
		(fp_line
			(start 0.120396 0.2794)
			(end -0.12065 0.2794)
			(stroke
				(width 0.1)
				(type default)
			)
			(layer "F.Fab")
		)
		(fp_line
			(start -0.12065 0.3048)
			(end -0.67945 0.3048)
			(stroke
				(width 0.1)
				(type default)
			)
			(layer "F.Fab")
		)
		(fp_line
			(start -0.12065 0.2794)
			(end -0.12065 0.3048)
			(stroke
				(width 0.1)
				(type default)
			)
			(layer "F.Fab")
		)
		(fp_line
			(start -0.12065 -0.2794)
			(end 0.12065 -0.2794)
			(stroke
				(width 0.1)
				(type default)
			)
			(layer "F.Fab")
		)
		(fp_line
			(start -0.12065 -0.305054)
			(end -0.12065 -0.2794)
			(stroke
				(width 0.1)
				(type default)
			)
			(layer "F.Fab")
		)
		(fp_line
			(start -0.67945 0.3048)
			(end -0.67945 -0.305054)
			(stroke
				(width 0.1)
				(type default)
			)
			(layer "F.Fab")
		)
		(fp_line
			(start -0.67945 -0.305054)
			(end -0.12065 -0.305054)
			(stroke
				(width 0.1)
				(type default)
			)
			(layer "F.Fab")
		)
		(pad "1" smd circle
			(at -0.40005 0 180)
			(size 0 0)
			(layers "F.Cu" "F.Mask" "F.Paste")
			(net "USB_HOST_BMC_A_DP")
		)
		(pad "2" smd circle
			(at 0.40005 0 180)
			(size 0 0)
			(layers "F.Cu" "F.Mask" "F.Paste")
			(net "GND")
		)
	)
	(footprint ""
		(layer "F.Cu")
		(at 57.023 -77.3684)
		(property "Reference" "R555"
			(at 0 0 0)
			(layer "F.SilkS")
			(hide yes)
			(effects
				(font
					(size 1.27 1.27)
				)
			)
		)
		(property "Value" ""
			(at 0 0 0)
			(layer "F.Fab")
			(effects
				(font
					(size 1.27 1.27)
				)
			)
		)
		(duplicate_pad_numbers_are_jumpers no)
		(fp_line
			(start -0.7874 -0.4064)
			(end 0.7874 -0.4064)
			(stroke
				(width 0.1524)
				(type default)
			)
			(layer "F.SilkS")
		)
		(fp_line
			(start -0.7874 0.4064)
			(end -0.7874 -0.4064)
			(stroke
				(width 0.1524)
				(type default)
			)
			(layer "F.SilkS")
		)
		(fp_line
			(start 0.7874 -0.4064)
			(end 0.7874 0.4064)
			(stroke
				(width 0.1524)
				(type default)
			)
			(layer "F.SilkS")
		)
		(fp_line
			(start 0.7874 0.4064)
			(end -0.7874 0.4064)
			(stroke
				(width 0.1524)
				(type default)
			)
			(layer "F.SilkS")
		)
		(fp_line
			(start -0.67945 -0.305054)
			(end -0.12065 -0.305054)
			(stroke
				(width 0.1)
				(type default)
			)
			(layer "F.Fab")
		)
		(fp_line
			(start -0.67945 0.3048)
			(end -0.67945 -0.305054)
			(stroke
				(width 0.1)
				(type default)
			)
			(layer "F.Fab")
		)
		(fp_line
			(start -0.12065 -0.305054)
			(end -0.12065 -0.2794)
			(stroke
				(width 0.1)
				(type default)
			)
			(layer "F.Fab")
		)
		(fp_line
			(start -0.12065 -0.2794)
			(end 0.12065 -0.2794)
			(stroke
				(width 0.1)
				(type default)
			)
			(layer "F.Fab")
		)
		(fp_line
			(start -0.12065 0.2794)
			(end -0.12065 0.3048)
			(stroke
				(width 0.1)
				(type default)
			)
			(layer "F.Fab")
		)
		(fp_line
			(start -0.12065 0.3048)
			(end -0.67945 0.3048)
			(stroke
				(width 0.1)
				(type default)
			)
			(layer "F.Fab")
		)
		(fp_line
			(start 0.120396 0.2794)
			(end -0.12065 0.2794)
			(stroke
				(width 0.1)
				(type default)
			)
			(layer "F.Fab")
		)
		(fp_line
			(start 0.120396 0.3048)
			(end 0.120396 0.2794)
			(stroke
				(width 0.1)
				(type default)
			)
			(layer "F.Fab")
		)
		(fp_line
			(start 0.12065 -0.3048)
			(end 0.67945 -0.3048)
			(stroke
				(width 0.1)
				(type default)
			)
			(layer "F.Fab")
		)
		(fp_line
			(start 0.12065 -0.2794)
			(end 0.12065 -0.3048)
			(stroke
				(width 0.1)
				(type default)
			)
			(layer "F.Fab")
		)
		(fp_line
			(start 0.67945 -0.3048)
			(end 0.67945 0.3048)
			(stroke
				(width 0.1)
				(type default)
			)
			(layer "F.Fab")
		)
		(fp_line
			(start 0.67945 0.3048)
			(end 0.120396 0.3048)
			(stroke
				(width 0.1)
				(type default)
			)
			(layer "F.Fab")
		)
		(pad "1" smd circle
			(at -0.40005 0)
			(size 0 0)
			(layers "F.Cu" "F.Mask" "F.Paste")
			(net "FLASH_LATCH_Q_N_R")
		)
		(pad "2" smd circle
			(at 0.40005 0)
			(size 0 0)
			(layers "F.Cu" "F.Mask" "F.Paste")
			(net "FLASH_LATCH_Q_N_R1")
		)
	)
)
